(kicad_pcb
	(version 20241229)
	(generator "pcbnew")
	(generator_version "9.0")
	(general
		(thickness 1.62)
		(legacy_teardrops no)
	)
	(paper "A3")
	(title_block
		(title "COM Express 7 Baseboard")
		(date "2025-02-04")
		(rev "1.1.2")
		(company "Antmicro Ltd")
		(comment 1 "www.antmicro.com")
		(comment 9 "footprints 93-96 of 802")
	)
	(layers
		(0 "F.Cu" signal)
		(4 "In1.Cu" signal)
		(6 "In2.Cu" signal)
		(8 "In3.Cu" signal)
		(10 "In4.Cu" signal)
		(12 "In5.Cu" signal)
		(14 "In6.Cu" signal)
		(2 "B.Cu" signal)
		(9 "F.Adhes" user "F.Adhesive")
		(11 "B.Adhes" user "B.Adhesive")
		(13 "F.Paste" user)
		(15 "B.Paste" user)
		(5 "F.SilkS" user "F.Silkscreen")
		(7 "B.SilkS" user "B.Silkscreen")
		(1 "F.Mask" user)
		(3 "B.Mask" user)
		(17 "Dwgs.User" user "User.Drawings")
		(19 "Cmts.User" user "User.Comments")
		(21 "Eco1.User" user "User.Eco1")
		(23 "Eco2.User" user "User.Eco2")
		(25 "Edge.Cuts" user)
		(27 "Margin" user)
		(31 "F.CrtYd" user "F.Courtyard")
		(29 "B.CrtYd" user "B.Courtyard")
		(35 "F.Fab" user)
		(33 "B.Fab" user)
	)
	(footprint "antmicro-footprints:SOT-23-5"
		(layer "F.Cu")
		(at 255.825 127.16)
		(property "Reference" "U32"
			(at 0.275 -1.8 90)
			(layer "F.SilkS")
			(effects
				(font
					(size 0.7 0.7)
					(thickness 0.15)
				)
				(justify left bottom)
			)
		)
		(property "Value" "TPS3840PL30DBVR"
			(at 0.002 2.799 0)
			(layer "F.Fab")
			(effects
				(font
					(size 0.7 0.7)
					(thickness 0.15)
				)
				(justify left bottom)
			)
		)
		(property "Datasheet" "https://www.ti.com/lit/ds/symlink/tps3840.pdf?HQS=dis-mous-null-mousermode-dsf-pf-null-wwe&DCM=yes&ref_url=https%3A%2F%2Fwww.mouser.com%2F&distId=26"
			(at 0 0 0)
			(layer "F.Fab")
			(hide yes)
			(effects
				(font
					(size 1.27 1.27)
					(thickness 0.15)
				)
			)
		)
		(property "Author" "Antmicro"
			(at 0 0 0)
			(layer "F.Fab")
			(hide yes)
			(effects
				(font
					(size 1 1)
					(thickness 0.15)
				)
			)
		)
		(property "License" "Apache-2.0"
			(at 0 0 0)
			(layer "F.Fab")
			(hide yes)
			(effects
				(font
					(size 1 1)
					(thickness 0.15)
				)
			)
		)
		(property "MPN" "TPS3840PL30DBVR"
			(at 0 0 0)
			(layer "F.Fab")
			(hide yes)
			(effects
				(font
					(size 1 1)
					(thickness 0.15)
				)
			)
		)
		(property "Manufacturer" "Texas Instruments"
			(at 0 0 0)
			(layer "F.Fab")
			(hide yes)
			(effects
				(font
					(size 1 1)
					(thickness 0.15)
				)
			)
		)
		(property ki_fp_filters "DBV0005A_N DBV0005A_M DBV0005A_L")
		(sheetname "Com Express 7 MGMT")
		(sheetfile "com_express_7_mgmt.kicad_sch")
		(attr smd)
		(fp_line
			(start -0.85 1.6)
			(end -0.85 1.301)
			(stroke
				(width 0.15)
				(type solid)
			)
			(layer "F.SilkS")
		)
		(fp_line
			(start -0.8 -1.6)
			(end -0.8 -1.3)
			(stroke
				(width 0.15)
				(type solid)
			)
			(layer "F.SilkS")
		)
		(fp_line
			(start -0.8 -1.6)
			(end -0.5 -1.6)
			(stroke
				(width 0.15)
				(type solid)
			)
			(layer "F.SilkS")
		)
		(fp_line
			(start -0.55 1.6)
			(end -0.85 1.6)
			(stroke
				(width 0.15)
				(type solid)
			)
			(layer "F.SilkS")
		)
		(fp_line
			(start 0.8 -1.6)
			(end 0.5 -1.6)
			(stroke
				(width 0.15)
				(type solid)
			)
			(layer "F.SilkS")
		)
		(fp_line
			(start 0.8 -1.3)
			(end 0.8 -1.6)
			(stroke
				(width 0.15)
				(type solid)
			)
			(layer "F.SilkS")
		)
		(fp_line
			(start 0.8 0.55)
			(end 0.8 -0.55)
			(stroke
				(width 0.15)
				(type solid)
			)
			(layer "F.SilkS")
		)
		(fp_line
			(start 0.8 1.3)
			(end 0.8 1.599)
			(stroke
				(width 0.15)
				(type solid)
			)
			(layer "F.SilkS")
		)
		(fp_line
			(start 0.8 1.599)
			(end 0.549 1.599)
			(stroke
				(width 0.15)
				(type solid)
			)
			(layer "F.SilkS")
		)
		(fp_circle
			(center -1.25 -1.5)
			(end -1.2 -1.5)
			(stroke
				(width 0.15)
				(type solid)
			)
			(fill yes)
			(layer "F.SilkS")
		)
		(fp_rect
			(start 1.9 -1.76)
			(end -1.9 1.75)
			(stroke
				(width 0.05)
				(type solid)
			)
			(fill no)
			(layer "F.CrtYd")
		)
		(fp_line
			(start -0.398 -1.526)
			(end -0.874 -1.05)
			(stroke
				(width 0.15)
				(type solid)
			)
			(layer "F.Fab")
		)
		(fp_rect
			(start 0.874 1.523)
			(end -0.873 -1.525)
			(stroke
				(width 0.15)
				(type solid)
			)
			(fill no)
			(layer "F.Fab")
		)
		(pad "1" smd rect
			(at -1.351 -0.951 270)
			(size 0.55 1)
			(layers "F.Cu" "F.Mask" "F.Paste")
			(net 545 "Net-(Q11-G)")
			(pinfunction "~{RESET}")
			(pintype "output")
			(teardrops
				(best_length_ratio 0.2)
				(max_length 1)
				(best_width_ratio 0.9)
				(max_width 2)
				(curved_edges yes)
				(filter_ratio 0.9)
				(enabled yes)
				(allow_two_segments yes)
				(prefer_zone_connections yes)
			)
		)
		(pad "2" smd rect
			(at -1.351 0 270)
			(size 0.55 1)
			(layers "F.Cu" "F.Mask" "F.Paste")
			(net 73 "+3V3_AON")
			(pinfunction "VDD")
			(pintype "power_in")
			(teardrops
				(best_length_ratio 0.2)
				(max_length 1)
				(best_width_ratio 0.9)
				(max_width 2)
				(curved_edges yes)
				(filter_ratio 0.9)
				(enabled yes)
				(allow_two_segments yes)
				(prefer_zone_connections yes)
			)
		)
		(pad "3" smd rect
			(at -1.351 0.949 270)
			(size 0.55 1)
			(layers "F.Cu" "F.Mask" "F.Paste")
			(net 1 "GND")
			(pinfunction "GND")
			(pintype "power_in")
			(teardrops
				(best_length_ratio 0.2)
				(max_length 1)
				(best_width_ratio 0.9)
				(max_width 2)
				(curved_edges yes)
				(filter_ratio 0.9)
				(enabled yes)
				(allow_two_segments yes)
				(prefer_zone_connections yes)
			)
		)
		(pad "4" smd rect
			(at 1.35 0.949 270)
			(size 0.55 1)
			(layers "F.Cu" "F.Mask" "F.Paste")
			(net 708 "Net-(U32-~{MR})")
			(pinfunction "~{MR}")
			(pintype "input")
			(teardrops
				(best_length_ratio 0.2)
				(max_length 1)
				(best_width_ratio 0.9)
				(max_width 2)
				(curved_edges yes)
				(filter_ratio 0.9)
				(enabled yes)
				(allow_two_segments yes)
				(prefer_zone_connections yes)
			)
		)
		(pad "5" smd rect
			(at 1.35 -0.951 270)
			(size 0.55 1)
			(layers "F.Cu" "F.Mask" "F.Paste")
			(net 82 "Net-(U32-CT)")
			(pinfunction "CT")
			(pintype "passive")
			(teardrops
				(best_length_ratio 0.2)
				(max_length 1)
				(best_width_ratio 0.9)
				(max_width 2)
				(curved_edges yes)
				(filter_ratio 0.9)
				(enabled yes)
				(allow_two_segments yes)
				(prefer_zone_connections yes)
			)
		)
	)
	(footprint "antmicro-footprints:SC70-3"
		(layer "F.Cu")
		(at 108.33 79)
		(property "Reference" "D9"
			(at 1.85 1.9 90)
			(layer "F.SilkS")
			(effects
				(font
					(size 0.7 0.7)
					(thickness 0.15)
				)
				(justify left bottom)
			)
		)
		(property "Value" "TPD2E2U06_SC70"
			(at 0 2.3 0)
			(layer "F.Fab")
			(effects
				(font
					(size 0.7 0.7)
					(thickness 0.15)
				)
				(justify left bottom)
			)
		)
		(property "Datasheet" "https://www.ti.com/lit/ds/symlink/tpd2e2u06.pdf?ts=1706006131823&ref_url=https%253A%252F%252Fwww.ti.com%252Finterface%252Fdiodes%252Fesd-protection-diodes%252Fproducts.html"
			(at 0 0 0)
			(layer "F.Fab")
			(hide yes)
			(effects
				(font
					(size 1.27 1.27)
					(thickness 0.15)
				)
			)
		)
		(property "Author" "Antmicro"
			(at 0 0 0)
			(layer "F.Fab")
			(hide yes)
			(effects
				(font
					(size 1 1)
					(thickness 0.15)
				)
			)
		)
		(property "License" "Apache-2.0"
			(at 0 0 0)
			(layer "F.Fab")
			(hide yes)
			(effects
				(font
					(size 1 1)
					(thickness 0.15)
				)
			)
		)
		(property "MPN" "TPD2E2U06DCKR"
			(at 0 0 0)
			(layer "F.Fab")
			(hide yes)
			(effects
				(font
					(size 1 1)
					(thickness 0.15)
				)
			)
		)
		(property "Manufacturer" "Texas Instruments"
			(at 0 0 0)
			(layer "F.Fab")
			(hide yes)
			(effects
				(font
					(size 1 1)
					(thickness 0.15)
				)
			)
		)
		(sheetname "USB-C console")
		(sheetfile "usb-c_console.kicad_sch")
		(attr smd)
		(fp_line
			(start -0.3 -1)
			(end 0.627 -0.999)
			(stroke
				(width 0.15)
				(type solid)
			)
			(layer "F.SilkS")
		)
		(fp_line
			(start -0.3 1)
			(end 0.627 1.001)
			(stroke
				(width 0.15)
				(type solid)
			)
			(layer "F.SilkS")
		)
		(fp_line
			(start 0.627 -0.6)
			(end 0.627 -0.999)
			(stroke
				(width 0.15)
				(type solid)
			)
			(layer "F.SilkS")
		)
		(fp_line
			(start 0.627 0.6)
			(end 0.627 1.001)
			(stroke
				(width 0.15)
				(type solid)
			)
			(layer "F.SilkS")
		)
		(fp_line
			(start -1.4 1)
			(end -1.4 -1)
			(stroke
				(width 0.05)
				(type solid)
			)
			(layer "F.CrtYd")
		)
		(fp_line
			(start -0.9 -1.3)
			(end -0.9 -1)
			(stroke
				(width 0.05)
				(type solid)
			)
			(layer "F.CrtYd")
		)
		(fp_line
			(start -0.9 -1.3)
			(end 0.9 -1.3)
			(stroke
				(width 0.05)
				(type solid)
			)
			(layer "F.CrtYd")
		)
		(fp_line
			(start -0.9 -1)
			(end -1.4 -1)
			(stroke
				(width 0.05)
				(type solid)
			)
			(layer "F.CrtYd")
		)
		(fp_line
			(start -0.9 1)
			(end -1.4 1)
			(stroke
				(width 0.05)
				(type solid)
			)
			(layer "F.CrtYd")
		)
		(fp_line
			(start -0.9 1.3)
			(end -0.9 1)
			(stroke
				(width 0.05)
				(type solid)
			)
			(layer "F.CrtYd")
		)
		(fp_line
			(start 0.9 -1.3)
			(end 0.9 -0.4)
			(stroke
				(width 0.05)
				(type solid)
			)
			(layer "F.CrtYd")
		)
		(fp_line
			(start 0.9 -0.4)
			(end 1.4 -0.4)
			(stroke
				(width 0.05)
				(type solid)
			)
			(layer "F.CrtYd")
		)
		(fp_line
			(start 0.9 0.4)
			(end 0.9 1.3)
			(stroke
				(width 0.05)
				(type solid)
			)
			(layer "F.CrtYd")
		)
		(fp_line
			(start 0.9 1.3)
			(end -0.9 1.3)
			(stroke
				(width 0.05)
				(type solid)
			)
			(layer "F.CrtYd")
		)
		(fp_line
			(start 1.4 -0.4)
			(end 1.4 0.4)
			(stroke
				(width 0.05)
				(type solid)
			)
			(layer "F.CrtYd")
		)
		(fp_line
			(start 1.4 0.4)
			(end 0.9 0.4)
			(stroke
				(width 0.05)
				(type solid)
			)
			(layer "F.CrtYd")
		)
		(fp_rect
			(start -0.623 -0.999)
			(end 0.627 1.001)
			(stroke
				(width 0.15)
				(type solid)
			)
			(fill no)
			(layer "F.Fab")
		)
		(pad "1" smd rect
			(at -1.051 -0.65 90)
			(size 0.6 0.6)
			(layers "F.Cu" "F.Mask" "F.Paste")
			(net 55 "/USB-C console/USB_D+")
			(pinfunction "1")
			(pintype "passive")
			(teardrops
				(best_length_ratio 0.2)
				(max_length 1)
				(best_width_ratio 0.9)
				(max_width 2)
				(curved_edges yes)
				(filter_ratio 0.9)
				(enabled yes)
				(allow_two_segments yes)
				(prefer_zone_connections yes)
			)
		)
		(pad "2" smd rect
			(at -1.051 0.65 90)
			(size 0.6 0.6)
			(layers "F.Cu" "F.Mask" "F.Paste")
			(net 56 "/USB-C console/USB_D-")
			(pinfunction "2")
			(pintype "passive")
			(teardrops
				(best_length_ratio 0.2)
				(max_length 1)
				(best_width_ratio 0.9)
				(max_width 2)
				(curved_edges yes)
				(filter_ratio 0.9)
				(enabled yes)
				(allow_two_segments yes)
				(prefer_zone_connections yes)
			)
		)
		(pad "3" smd rect
			(at 1.05 0 90)
			(size 0.6 0.6)
			(layers "F.Cu" "F.Mask" "F.Paste")
			(net 1 "GND")
			(pinfunction "3")
			(pintype "passive")
			(teardrops
				(best_length_ratio 0.2)
				(max_length 1)
				(best_width_ratio 0.9)
				(max_width 2)
				(curved_edges yes)
				(filter_ratio 0.9)
				(enabled yes)
				(allow_two_segments yes)
				(prefer_zone_connections yes)
			)
		)
	)
	(footprint "antmicro-footprints:R_0402_1005Metric"
		(layer "F.Cu")
		(at 122.05 90.96)
		(descr "Resistor SMD 0402")
		(tags "resistor SMD 0402")
		(property "Reference" "R25"
			(at 0.75 0.44 0)
			(layer "F.SilkS")
			(effects
				(font
					(size 0.7 0.7)
					(thickness 0.15)
				)
				(justify left bottom)
			)
		)
		(property "Value" "R_10k_0402"
			(at -1.011843 1.772047 0)
			(layer "F.Fab")
			(effects
				(font
					(size 0.7 0.7)
					(thickness 0.15)
				)
				(justify left bottom)
			)
		)
		(property "Datasheet" "https://www.bourns.com/docs/product-datasheets/cr.pdf"
			(at 0 0 0)
			(layer "F.Fab")
			(hide yes)
			(effects
				(font
					(size 1.27 1.27)
					(thickness 0.15)
				)
			)
		)
		(property "Author" "Antmicro"
			(at 0 0 0)
			(layer "F.Fab")
			(hide yes)
			(effects
				(font
					(size 1 1)
					(thickness 0.15)
				)
			)
		)
		(property "License" "Apache-2.0"
			(at 0 0 0)
			(layer "F.Fab")
			(hide yes)
			(effects
				(font
					(size 1 1)
					(thickness 0.15)
				)
			)
		)
		(property "MPN" "CR0402-FX-1002GLF"
			(at 0 0 0)
			(layer "F.Fab")
			(hide yes)
			(effects
				(font
					(size 1 1)
					(thickness 0.15)
				)
			)
		)
		(property "Manufacturer" "Bourns"
			(at 0 0 0)
			(layer "F.Fab")
			(hide yes)
			(effects
				(font
					(size 1 1)
					(thickness 0.15)
				)
			)
		)
		(property "Public" "False"
			(at 0 0 0)
			(layer "F.Fab")
			(hide yes)
			(effects
				(font
					(size 1 1)
					(thickness 0.15)
				)
			)
		)
		(property "Tolerance" "1%"
			(at 0 0 0)
			(layer "F.Fab")
			(hide yes)
			(effects
				(font
					(size 1 1)
					(thickness 0.15)
				)
			)
		)
		(property "Val" "10k"
			(at 0 0 0)
			(layer "F.Fab")
			(hide yes)
			(effects
				(font
					(size 1 1)
					(thickness 0.15)
				)
			)
		)
		(sheetname "2xUSB3.0+RJ45")
		(sheetfile "usb3+rj45.kicad_sch")
		(attr smd)
		(fp_rect
			(start -0.925 -0.47)
			(end 0.925 0.47)
			(stroke
				(width 0.05)
				(type default)
			)
			(fill no)
			(layer "F.CrtYd")
		)
		(fp_rect
			(start -0.5 -0.25)
			(end 0.5 0.25)
			(stroke
				(width 0.15)
				(type solid)
			)
			(fill no)
			(layer "F.Fab")
		)
		(pad "1" smd roundrect
			(at -0.48 0)
			(size 0.59 0.64)
			(layers "F.Cu" "F.Mask" "F.Paste")
			(roundrect_rratio 0.25)
			(net 556 "/2xUSB3.0+RJ45/EN_2B")
			(pintype "passive")
			(teardrops
				(best_length_ratio 0.2)
				(max_length 1)
				(best_width_ratio 0.9)
				(max_width 2)
				(curved_edges yes)
				(filter_ratio 0.9)
				(enabled yes)
				(allow_two_segments yes)
				(prefer_zone_connections yes)
			)
		)
		(pad "2" smd roundrect
			(at 0.48 0)
			(size 0.59 0.64)
			(layers "F.Cu" "F.Mask" "F.Paste")
			(roundrect_rratio 0.25)
			(net 2 "+3V3")
			(pintype "passive")
			(teardrops
				(best_length_ratio 0.2)
				(max_length 1)
				(best_width_ratio 0.9)
				(max_width 2)
				(curved_edges yes)
				(filter_ratio 0.9)
				(enabled yes)
				(allow_two_segments yes)
				(prefer_zone_connections yes)
			)
		)
	)
	(footprint "antmicro-footprints:R_0805_2012Metric"
		(layer "F.Cu")
		(at 304.25 96.74 180)
		(property "Reference" "R113"
			(at -1.45 0.93 0)
			(layer "F.SilkS")
			(effects
				(font
					(size 0.7 0.7)
					(thickness 0.15)
				)
				(justify right bottom)
			)
		)
		(property "Value" "R_0R001_0805"
			(at 1.82 -3.52 0)
			(layer "F.Fab")
			(effects
				(font
					(size 0.7 0.7)
					(thickness 0.15)
				)
				(justify left bottom mirror)
			)
		)
		(property "Datasheet" "https://www.eaton.com/content/dam/eaton/products/electronic-components/resources/data-sheet/eaton-msma-automotive-smd-current-sense-resistor-metal-strip-data-sheet-elx1179.pdf"
			(at 0 0 180)
			(layer "F.Fab")
			(hide yes)
			(effects
				(font
					(size 1.27 1.27)
					(thickness 0.15)
				)
			)
		)
		(property "Author" "Antmicro"
			(at 608.5 193.48 0)
			(layer "F.Fab")
			(hide yes)
			(effects
				(font
					(size 1 1)
					(thickness 0.15)
				)
			)
		)
		(property "License" "Apache-2.0"
			(at 608.5 193.48 0)
			(layer "F.Fab")
			(hide yes)
			(effects
				(font
					(size 1 1)
					(thickness 0.15)
				)
			)
		)
		(property "MPN" "MSMA0805R0010FSM"
			(at 608.5 193.48 0)
			(layer "F.Fab")
			(hide yes)
			(effects
				(font
					(size 1 1)
					(thickness 0.15)
				)
			)
		)
		(property "Manufacturer" "Eaton"
			(at 608.5 193.48 0)
			(layer "F.Fab")
			(hide yes)
			(effects
				(font
					(size 1 1)
					(thickness 0.15)
				)
			)
		)
		(property "Public" "False"
			(at 608.5 193.48 0)
			(layer "F.Fab")
			(hide yes)
			(effects
				(font
					(size 1 1)
					(thickness 0.15)
				)
			)
		)
		(property "Tolerance" "1%"
			(at 608.5 193.48 0)
			(layer "F.Fab")
			(hide yes)
			(effects
				(font
					(size 1 1)
					(thickness 0.15)
				)
			)
		)
		(property "Val" "0R001"
			(at 608.5 193.48 0)
			(layer "F.Fab")
			(hide yes)
			(effects
				(font
					(size 1 1)
					(thickness 0.15)
				)
			)
		)
		(sheetname "Power")
		(sheetfile "power.kicad_sch")
		(attr smd)
		(fp_line
			(start -0.3 -0.701)
			(end 0.298 -0.701)
			(stroke
				(width 0.15)
				(type solid)
			)
			(layer "F.SilkS")
		)
		(fp_line
			(start -0.32 0.699)
			(end 0.28 0.699)
			(stroke
				(width 0.15)
				(type solid)
			)
			(layer "F.SilkS")
		)
		(fp_rect
			(start 1.95 -0.9)
			(end -1.95 0.9)
			(stroke
				(width 0.05)
				(type default)
			)
			(fill no)
			(layer "F.CrtYd")
		)
		(fp_line
			(start 0.949 -0.677)
			(end 0.949 0.675)
			(stroke
				(width 0.15)
				(type solid)
			)
			(layer "F.Fab")
		)
		(fp_line
			(start -0.951 0.68)
			(end 0.949 0.68)
			(stroke
				(width 0.15)
				(type solid)
			)
			(layer "F.Fab")
		)
		(fp_line
			(start -0.951 -0.677)
			(end -0.951 0.675)
			(stroke
				(width 0.15)
				(type solid)
			)
			(layer "F.Fab")
		)
		(fp_line
			(start -0.951 -0.682)
			(end 0.949 -0.682)
			(stroke
				(width 0.15)
				(type solid)
			)
			(layer "F.Fab")
		)
		(pad "1" smd roundrect
			(at -1.1 0 180)
			(size 1.2 1.3)
			(layers "F.Cu" "F.Mask" "F.Paste")
			(roundrect_rratio 0.25)
			(net 75 "Net-(U50-IN+)")
			(pintype "passive")
			(teardrops
				(best_length_ratio 0.2)
				(max_length 1)
				(best_width_ratio 0.9)
				(max_width 2)
				(curved_edges yes)
				(filter_ratio 0.9)
				(enabled yes)
				(allow_two_segments yes)
				(prefer_zone_connections yes)
			)
		)
		(pad "2" smd roundrect
			(at 1.1 0 180)
			(size 1.2 1.3)
			(layers "F.Cu" "F.Mask" "F.Paste")
			(roundrect_rratio 0.25)
			(net 77 "+5V_AON")
			(pintype "passive")
			(teardrops
				(best_length_ratio 0.2)
				(max_length 1)
				(best_width_ratio 0.9)
				(max_width 2)
				(curved_edges yes)
				(filter_ratio 0.9)
				(enabled yes)
				(allow_two_segments yes)
				(prefer_zone_connections yes)
			)
		)
	)
)
